# BASEBOARD_FAB2 (Tioga Pass) — schematic netlist excerpt (pin names and nets, part order shuffled) for the footprints in the layout excerpt that follows; sources: Cadence DE-HDL packaged netlist, KiCad conversion of Wiwynn_Tioga_Pass_MB.brd

C1A12  CAP  22UF 4V 20% X6S  pkg 0805LF  page 227 : A = PVDDQ_KLM ; B = GND
R9F34  RES  33.2 1% EMPTY  pkg 0402  page 151 : A = RST_BMC_DDR3_R_N ; B = BMC_M_RST_N
R25W187  RES  0.0 5% CHIP  pkg 0402  page 255 : A = JTAG_BMC_BUF_TDO_R ; B = JTAG_BMC_BUF_TDO

(kicad_pcb
	(version 20260206)
	(generator "pcbnew")
	(generator_version "10.0")
	(general
		(thickness 1.6)
		(legacy_teardrops no)
	)
	(paper "A4")
	(title_block
		(title "Wiwynn_Tioga_Pass_MB.brd")
		(comment 1 "Tioga Pass / footprints 930-932 of 4770")
	)
	(layers
		(0 "F.Cu" signal "TOP")
		(4 "In1.Cu" signal "L2GND")
		(6 "In2.Cu" signal "L3")
		(8 "In3.Cu" signal "L4GND")
		(10 "In4.Cu" signal "L5")
		(12 "In5.Cu" signal "L6GND")
		(14 "In6.Cu" signal "L7VCC")
		(16 "In7.Cu" signal "L8VCC")
		(18 "In8.Cu" signal "L9GND")
		(20 "In9.Cu" signal "L10")
		(22 "In10.Cu" signal "L11GND")
		(24 "In11.Cu" signal "L12")
		(26 "In12.Cu" signal "L13GND")
		(2 "B.Cu" signal "BOTTOM")
		(9 "F.Adhes" user "F.Adhesive")
		(11 "B.Adhes" user "B.Adhesive")
		(13 "F.Paste" user "Package Geometry/Pastemask Top")
		(15 "B.Paste" user "Package Geometry/Pastemask Bottom")
		(5 "F.SilkS" user "Ref Des/Silkscreen Top")
		(7 "B.SilkS" user "Ref Des/Silkscreen Bottom")
		(1 "F.Mask" user "Board Geometry/Soldermask Top")
		(3 "B.Mask" user "Board Geometry/Soldermask Bottom")
		(17 "Dwgs.User" user "User.Drawings")
		(19 "Cmts.User" user "User.Comments")
		(21 "Eco1.User" user "User.Eco1")
		(23 "Eco2.User" user "User.Eco2")
		(25 "Edge.Cuts" user "Board Geometry/Outline")
		(27 "Margin" user)
		(31 "F.CrtYd" user "Package Geometry/Place Bound Top")
		(29 "B.CrtYd" user "Package Geometry/Place Bound Bottom")
		(35 "F.Fab" user "Ref Des/Assembly Top")
		(33 "B.Fab" user "Ref Des/Assembly Bottom")
	)
	(footprint ""
		(layer "F.Cu")
		(at 13.843 -142.875 -90)
		(property "Reference" "C1A12"
			(at 1.47828 0.78994 180)
			(unlocked yes)
			(layer "F.SilkS")
			(effects
				(font
					(size 0.4064 0.254)
					(thickness 0.1524)
				)
			)
		)
		(property "Value" ""
			(at 0 0 270)
			(layer "F.Fab")
			(effects
				(font
					(size 1.27 1.27)
				)
			)
		)
		(duplicate_pad_numbers_are_jumpers no)
		(fp_poly
			(pts
				(xy -0.7239 -0.2159) (xy 0.7239 -0.2159) (xy 0.7239 1.9939) (xy -0.7239 1.9939)
			)
			(stroke
				(width 0)
				(type default)
			)
			(fill no)
			(layer "F.CrtYd")
		)
		(fp_line
			(start -0.7239 1.9939)
			(end 0.7239 1.9939)
			(stroke
				(width 0.1)
				(type default)
			)
			(layer "F.Fab")
		)
		(fp_line
			(start 0.7239 1.9939)
			(end 0.7239 -0.2159)
			(stroke
				(width 0.1)
				(type default)
			)
			(layer "F.Fab")
		)
		(fp_line
			(start -0.7239 -0.2159)
			(end -0.7239 1.9939)
			(stroke
				(width 0.1)
				(type default)
			)
			(layer "F.Fab")
		)
		(fp_line
			(start 0.7239 -0.2159)
			(end -0.7239 -0.2159)
			(stroke
				(width 0.1)
				(type default)
			)
			(layer "F.Fab")
		)
		(pad "1" smd rect
			(at 0 0 270)
			(size 1.27 1.016)
			(layers "F.Cu" "F.Mask" "F.Paste")
			(net "PVDDQ_KLM")
		)
		(pad "2" smd rect
			(at 0 1.778 270)
			(size 1.27 1.016)
			(layers "F.Cu" "F.Mask" "F.Paste")
			(net "GND")
		)
		(zone
			(layer "F.Cu")
			(hatch none 0.5)
			(connect_pads
				(clearance 0)
			)
			(min_thickness 0.25)
			(keepout
				(tracks not_allowed)
				(vias allowed)
				(pads allowed)
				(copperpour not_allowed)
				(footprints allowed)
			)
			(placement
				(enabled no)
				(sheetname "")
			)
			(fill
				(thermal_gap 0.5)
				(thermal_bridge_width 0.5)
				(island_removal_mode 0)
			)
			(polygon
				(pts
					(xy 13.335 -143.51) (xy 13.335 -142.24) (xy 12.573 -142.24) (xy 12.573 -143.51)
				)
			)
		)
	)
	(footprint ""
		(layer "F.Cu")
		(at 448.35572 -153.54046 -90)
		(property "Reference" "R25W187"
			(at -0.8382 -0.67818 270)
			(unlocked yes)
			(layer "F.SilkS")
			(effects
				(font
					(size 0.4064 0.254)
					(thickness 0.1524)
				)
				(justify left)
			)
		)
		(property "Value" ""
			(at 0 0 270)
			(layer "F.Fab")
			(effects
				(font
					(size 1.27 1.27)
				)
			)
		)
		(duplicate_pad_numbers_are_jumpers no)
		(fp_poly
			(pts
				(xy -0.2794 -0.1016) (xy 0.2794 -0.1016) (xy 0.2794 0.9906) (xy -0.2794 0.9906)
			)
			(stroke
				(width 0)
				(type default)
			)
			(fill no)
			(layer "F.CrtYd")
		)
		(fp_line
			(start -0.2794 0.9906)
			(end 0.2794 0.9906)
			(stroke
				(width 0.1)
				(type default)
			)
			(layer "F.Fab")
		)
		(fp_line
			(start 0.2794 0.9906)
			(end 0.2794 -0.1016)
			(stroke
				(width 0.1)
				(type default)
			)
			(layer "F.Fab")
		)
		(fp_line
			(start -0.2794 -0.1016)
			(end -0.2794 0.9906)
			(stroke
				(width 0.1)
				(type default)
			)
			(layer "F.Fab")
		)
		(fp_line
			(start 0.2794 -0.1016)
			(end -0.2794 -0.1016)
			(stroke
				(width 0.1)
				(type default)
			)
			(layer "F.Fab")
		)
		(pad "1" smd rect
			(at 0 0 270)
			(size 0.508 0.508)
			(layers "F.Cu" "F.Mask" "F.Paste")
			(net "JTAG_BMC_BUF_TDO_R")
		)
		(pad "2" smd rect
			(at 0 0.889 270)
			(size 0.508 0.508)
			(layers "F.Cu" "F.Mask" "F.Paste")
			(net "JTAG_BMC_BUF_TDO")
		)
		(zone
			(layer "F.Cu")
			(hatch none 0.5)
			(connect_pads
				(clearance 0)
			)
			(min_thickness 0.25)
			(keepout
				(tracks not_allowed)
				(vias allowed)
				(pads allowed)
				(copperpour not_allowed)
				(footprints allowed)
			)
			(placement
				(enabled no)
				(sheetname "")
			)
			(fill
				(thermal_gap 0.5)
				(thermal_bridge_width 0.5)
				(island_removal_mode 0)
			)
			(polygon
				(pts
					(xy 447.72072 -153.79446) (xy 447.72072 -153.28646) (xy 448.10172 -153.28646) (xy 448.10172 -153.79446)
				)
			)
		)
		(zone
			(layer "F.Cu")
			(hatch none 0.5)
			(connect_pads
				(clearance 0)
			)
			(min_thickness 0.25)
			(keepout
				(tracks allowed)
				(vias not_allowed)
				(pads allowed)
				(copperpour not_allowed)
				(footprints allowed)
			)
			(placement
				(enabled no)
				(sheetname "")
			)
			(fill
				(thermal_gap 0.5)
				(thermal_bridge_width 0.5)
				(island_removal_mode 0)
			)
			(polygon
				(pts
					(xy 448.10172 -153.79446) (xy 448.10172 -153.28646) (xy 447.72072 -153.28646) (xy 447.72072 -153.79446)
				)
			)
		)
	)
	(footprint ""
		(layer "F.Cu")
		(at 453.644 -41.021)
		(property "Reference" "R9F34"
			(at 0 0 0)
			(layer "F.SilkS")
			(hide yes)
			(effects
				(font
					(size 1.27 1.27)
				)
			)
		)
		(property "Value" ""
			(at 0 0 0)
			(layer "F.Fab")
			(effects
				(font
					(size 1.27 1.27)
				)
			)
		)
		(duplicate_pad_numbers_are_jumpers no)
		(fp_poly
			(pts
				(xy -0.2794 -0.1016) (xy 0.2794 -0.1016) (xy 0.2794 0.9906) (xy -0.2794 0.9906)
			)
			(stroke
				(width 0)
				(type default)
			)
			(fill no)
			(layer "F.CrtYd")
		)
		(fp_line
			(start -0.2794 -0.1016)
			(end -0.2794 0.9906)
			(stroke
				(width 0.1)
				(type default)
			)
			(layer "F.Fab")
		)
		(fp_line
			(start -0.2794 0.9906)
			(end 0.2794 0.9906)
			(stroke
				(width 0.1)
				(type default)
			)
			(layer "F.Fab")
		)
		(fp_line
			(start 0.2794 -0.1016)
			(end -0.2794 -0.1016)
			(stroke
				(width 0.1)
				(type default)
			)
			(layer "F.Fab")
		)
		(fp_line
			(start 0.2794 0.9906)
			(end 0.2794 -0.1016)
			(stroke
				(width 0.1)
				(type default)
			)
			(layer "F.Fab")
		)
		(pad "1" smd rect
			(at 0 0)
			(size 0.508 0.508)
			(layers "F.Cu" "F.Mask" "F.Paste")
			(net "RST_BMC_DDR3_R_N")
		)
		(pad "2" smd rect
			(at 0 0.889)
			(size 0.508 0.508)
			(layers "F.Cu" "F.Mask" "F.Paste")
			(net "BMC_M_RST_N")
		)
		(zone
			(layer "F.Cu")
			(hatch none 0.5)
			(connect_pads
				(clearance 0)
			)
			(min_thickness 0.25)
			(keepout
				(tracks allowed)
				(vias not_allowed)
				(pads allowed)
				(copperpour not_allowed)
				(footprints allowed)
			)
			(placement
				(enabled no)
				(sheetname "")
			)
			(fill
				(thermal_gap 0.5)
				(thermal_bridge_width 0.5)
				(island_removal_mode 0)
			)
			(polygon
				(pts
					(xy 453.39 -40.767) (xy 453.898 -40.767) (xy 453.898 -40.386) (xy 453.39 -40.386)
				)
			)
		)
		(zone
			(layer "F.Cu")
			(hatch none 0.5)
			(connect_pads
				(clearance 0)
			)
			(min_thickness 0.25)
			(keepout
				(tracks not_allowed)
				(vias allowed)
				(pads allowed)
				(copperpour not_allowed)
				(footprints allowed)
			)
			(placement
				(enabled no)
				(sheetname "")
			)
			(fill
				(thermal_gap 0.5)
				(thermal_bridge_width 0.5)
				(island_removal_mode 0)
			)
			(polygon
				(pts
					(xy 453.39 -40.386) (xy 453.898 -40.386) (xy 453.898 -40.767) (xy 453.39 -40.767)
				)
			)
		)
	)
)
